# Wiwynn_Honey Badger_Riser_Card_4L_Stackup_20150121.xlsx — Wiwynn (pcb-stackup)
|  |  |  |  |  |  |  |  |  |  |  | Single Ended Type(mil) |  |  |  |  | Differential Type(mil) |  |  |  |  |  |
|  |  |  |  |  |  |  |  |  |  | Imp | 50 |  |  |  | Imp | 85 |  |  |  |  |  |
|  |  |  |  |  |  |  |  |  |  | Variation | Inner /Outer ±5Ω |  |  |  | Variation | Inner 10% / Outer 10% |  |  |  |  |  |
|  |  |  |  |  |  |  |  |  |  | Bus | MISC |  |  |  | Bus | PCIe |  |  |  |  |  |
|  |  |  |  |  |  |  |  |  |  | Type | SE |  |  |  | Type | DP |  |  |  |  |  |
| Layer |  |  |  | Thickness |  | Glass style | Er |  | Df(1G) | Layers | All |  |  |  | Layers | All |  |  |  |  |  |
|  |  |  | Cu oz | Wiwynn | Vender |  | Wiwynn | Vender |  |  | Wiwynn |  | Vender |  |  | Wiwynn |  |  | Vender |  |  |
|  | Mask |  |  | 0.5 |  |  | 3.8 |  |  |  | Width | Imp | Width | Imp |  | Width | Space | Imp | Width | Space | Imp |
| Top | Signal |  | 0.5 oz + plating | 1.9 |  |  |  |  |  | S1 | 4.25 |  |  |  | S1 | 5.5 | 8 |  |  |  |  |
|  | Prepreg |  |  | 2.7 |  |  | 4 |  |  |  |  |  |  |  |  |  |  |  |  |  |  |
| L2 | PWR | GND | 1 oz | 1.3 |  |  |  |  |  | G2 | Reference layer |  | Reference layer |  | G2 | Reference layer |  |  | Reference layer |  |  |
|  | Core |  |  | 50 |  |  | 4.5 |  |  |  |  |  |  |  |  |  |  |  |  |  |  |
| L3 | GND |  | 1 oz | 1.3 |  |  |  |  |  | G3 | Reference layer |  | Reference layer |  | G3 | Reference layer |  |  | Reference layer |  |  |
|  | Prepreg |  |  | 2.7 |  |  | 4 |  |  |  |  |  |  |  |  |  |  |  |  |  |  |
| Bottom | Signal |  | 0.5 oz + plating | 1.9 |  |  |  |  |  | S4 | 4.25 |  |  |  | S4 | 5.5 | 8 |  |  |  |  |
|  | Mask |  |  | 0.5 |  |  | 3.8 |  |  |  |  |  |  |  |  |  |  |  |  |  |  |
| Thickness requirement: 1.6±10% mm |  |  | mil | 62.8 |  | +/-10% |  |  |  |  |  |  |  |  |  |  |  |  |  |  |  |
|  |  |  | mm | 1.5951231902463805 |  |  |  |  |  |  |  |  |  |  |  |  |  |  |  |  |  |
